# S9S_MB_2U (Grand Teton) — schematic netlist excerpt (pin names and nets, part order shuffled) for the footprints in the layout excerpt that follows; sources: Cadence DE-HDL packaged netlist, KiCad conversion of 03242023_DA0F0TMBIJ0_F0T_Motherboard_J_brd_V01_OCP.brd

R2991  Q_RES  33.2 1% CHIP  pkg 0402LF  page 234 : A = SMB_2_BMC_GPU_BUF_R_SDA ; B = SMB_2_BMC_GPU_BUF_SDA
R3304  Q_RES  0 5% CHIP  pkg 0402LF  page 165 : A = OCP_SFF_PRSNT_ALL_R_N ; B = OCP_SFF_PRSNT_ALL_R3_N

(kicad_pcb
	(version 20260206)
	(generator "pcbnew")
	(generator_version "10.0")
	(general
		(thickness 1.6)
		(legacy_teardrops no)
	)
	(paper "A4")
	(title_block
		(title "03242023_DA0F0TMBIJ0_F0T_Motherboard_J_brd_V01_OCP.brd")
		(comment 1 "Grand Teton / footprints 1691-1692 of 6105")
	)
	(layers
		(0 "F.Cu" signal "TOP")
		(4 "In1.Cu" signal "GND")
		(6 "In2.Cu" signal "IN1")
		(8 "In3.Cu" signal "GND1")
		(10 "In4.Cu" signal "IN2")
		(12 "In5.Cu" signal "GND2")
		(14 "In6.Cu" signal "IN3")
		(16 "In7.Cu" signal "GND3")
		(18 "In8.Cu" signal "VCC")
		(20 "In9.Cu" signal "VCC1")
		(22 "In10.Cu" signal "GND4")
		(24 "In11.Cu" signal "IN4")
		(26 "In12.Cu" signal "GND5")
		(28 "In13.Cu" signal "IN5")
		(30 "In14.Cu" signal "GND6")
		(32 "In15.Cu" signal "IN6")
		(34 "In16.Cu" signal "GND7")
		(2 "B.Cu" signal "BOTTOM")
		(9 "F.Adhes" user "F.Adhesive")
		(11 "B.Adhes" user "B.Adhesive")
		(13 "F.Paste" user "Package Geometry/Pastemask Top")
		(15 "B.Paste" user "Package Geometry/Pastemask Bottom")
		(5 "F.SilkS" user "Ref Des/Silkscreen Top")
		(7 "B.SilkS" user "Ref Des/Silkscreen Bottom")
		(1 "F.Mask" user "Board Geometry/Soldermask Top")
		(3 "B.Mask" user "Board Geometry/Soldermask Bottom")
		(17 "Dwgs.User" user "User.Drawings")
		(19 "Cmts.User" user "User.Comments")
		(21 "Eco1.User" user "User.Eco1")
		(23 "Eco2.User" user "User.Eco2")
		(25 "Edge.Cuts" user "Board Geometry/Outline")
		(27 "Margin" user)
		(31 "F.CrtYd" user "Package Geometry/Place Bound Top")
		(29 "B.CrtYd" user "Package Geometry/Place Bound Bottom")
		(35 "F.Fab" user "Ref Des/Assembly Top")
		(33 "B.Fab" user "Ref Des/Assembly Bottom")
	)
	(footprint ""
		(layer "F.Cu")
		(at 150.83028 -34.623756 180)
		(property "Reference" "R3304"
			(at 0 0 180)
			(layer "F.SilkS")
			(hide yes)
			(effects
				(font
					(size 1.27 1.27)
				)
			)
		)
		(property "Value" ""
			(at 0 0 180)
			(layer "F.Fab")
			(effects
				(font
					(size 1.27 1.27)
				)
			)
		)
		(duplicate_pad_numbers_are_jumpers no)
		(fp_line
			(start 0.7874 0.4064)
			(end -0.7874 0.4064)
			(stroke
				(width 0.1524)
				(type default)
			)
			(layer "F.SilkS")
		)
		(fp_line
			(start 0.7874 -0.4064)
			(end 0.7874 0.4064)
			(stroke
				(width 0.1524)
				(type default)
			)
			(layer "F.SilkS")
		)
		(fp_line
			(start -0.7874 0.4064)
			(end -0.7874 -0.4064)
			(stroke
				(width 0.1524)
				(type default)
			)
			(layer "F.SilkS")
		)
		(fp_line
			(start -0.7874 -0.4064)
			(end 0.7874 -0.4064)
			(stroke
				(width 0.1524)
				(type default)
			)
			(layer "F.SilkS")
		)
		(fp_line
			(start 0.67945 0.3048)
			(end 0.120396 0.3048)
			(stroke
				(width 0.1)
				(type default)
			)
			(layer "F.Fab")
		)
		(fp_line
			(start 0.67945 -0.3048)
			(end 0.67945 0.3048)
			(stroke
				(width 0.1)
				(type default)
			)
			(layer "F.Fab")
		)
		(fp_line
			(start 0.12065 -0.2794)
			(end 0.12065 -0.3048)
			(stroke
				(width 0.1)
				(type default)
			)
			(layer "F.Fab")
		)
		(fp_line
			(start 0.12065 -0.3048)
			(end 0.67945 -0.3048)
			(stroke
				(width 0.1)
				(type default)
			)
			(layer "F.Fab")
		)
		(fp_line
			(start 0.120396 0.3048)
			(end 0.120396 0.2794)
			(stroke
				(width 0.1)
				(type default)
			)
			(layer "F.Fab")
		)
		(fp_line
			(start 0.120396 0.2794)
			(end -0.12065 0.2794)
			(stroke
				(width 0.1)
				(type default)
			)
			(layer "F.Fab")
		)
		(fp_line
			(start -0.12065 0.3048)
			(end -0.67945 0.3048)
			(stroke
				(width 0.1)
				(type default)
			)
			(layer "F.Fab")
		)
		(fp_line
			(start -0.12065 0.2794)
			(end -0.12065 0.3048)
			(stroke
				(width 0.1)
				(type default)
			)
			(layer "F.Fab")
		)
		(fp_line
			(start -0.12065 -0.2794)
			(end 0.12065 -0.2794)
			(stroke
				(width 0.1)
				(type default)
			)
			(layer "F.Fab")
		)
		(fp_line
			(start -0.12065 -0.305054)
			(end -0.12065 -0.2794)
			(stroke
				(width 0.1)
				(type default)
			)
			(layer "F.Fab")
		)
		(fp_line
			(start -0.67945 0.3048)
			(end -0.67945 -0.305054)
			(stroke
				(width 0.1)
				(type default)
			)
			(layer "F.Fab")
		)
		(fp_line
			(start -0.67945 -0.305054)
			(end -0.12065 -0.305054)
			(stroke
				(width 0.1)
				(type default)
			)
			(layer "F.Fab")
		)
		(pad "1" smd circle
			(at -0.40005 0 180)
			(size 0 0)
			(layers "F.Cu" "F.Mask" "F.Paste")
			(net "OCP_SFF_PRSNT_ALL_R_N")
		)
		(pad "2" smd circle
			(at 0.40005 0 180)
			(size 0 0)
			(layers "F.Cu" "F.Mask" "F.Paste")
			(net "OCP_SFF_PRSNT_ALL_R3_N")
		)
	)
	(footprint ""
		(layer "F.Cu")
		(at 32.780478 -437.688228 180)
		(property "Reference" "R2991"
			(at 0 0 180)
			(layer "F.SilkS")
			(hide yes)
			(effects
				(font
					(size 1.27 1.27)
				)
			)
		)
		(property "Value" ""
			(at 0 0 180)
			(layer "F.Fab")
			(effects
				(font
					(size 1.27 1.27)
				)
			)
		)
		(duplicate_pad_numbers_are_jumpers no)
		(fp_line
			(start 0.7874 0.4064)
			(end -0.7874 0.4064)
			(stroke
				(width 0.1524)
				(type default)
			)
			(layer "F.SilkS")
		)
		(fp_line
			(start 0.7874 -0.4064)
			(end 0.7874 0.4064)
			(stroke
				(width 0.1524)
				(type default)
			)
			(layer "F.SilkS")
		)
		(fp_line
			(start -0.7874 0.4064)
			(end -0.7874 -0.4064)
			(stroke
				(width 0.1524)
				(type default)
			)
			(layer "F.SilkS")
		)
		(fp_line
			(start -0.7874 -0.4064)
			(end 0.7874 -0.4064)
			(stroke
				(width 0.1524)
				(type default)
			)
			(layer "F.SilkS")
		)
		(fp_line
			(start 0.67945 0.3048)
			(end 0.120396 0.3048)
			(stroke
				(width 0.1)
				(type default)
			)
			(layer "F.Fab")
		)
		(fp_line
			(start 0.67945 -0.3048)
			(end 0.67945 0.3048)
			(stroke
				(width 0.1)
				(type default)
			)
			(layer "F.Fab")
		)
		(fp_line
			(start 0.12065 -0.2794)
			(end 0.12065 -0.3048)
			(stroke
				(width 0.1)
				(type default)
			)
			(layer "F.Fab")
		)
		(fp_line
			(start 0.12065 -0.3048)
			(end 0.67945 -0.3048)
			(stroke
				(width 0.1)
				(type default)
			)
			(layer "F.Fab")
		)
		(fp_line
			(start 0.120396 0.3048)
			(end 0.120396 0.2794)
			(stroke
				(width 0.1)
				(type default)
			)
			(layer "F.Fab")
		)
		(fp_line
			(start 0.120396 0.2794)
			(end -0.12065 0.2794)
			(stroke
				(width 0.1)
				(type default)
			)
			(layer "F.Fab")
		)
		(fp_line
			(start -0.12065 0.3048)
			(end -0.67945 0.3048)
			(stroke
				(width 0.1)
				(type default)
			)
			(layer "F.Fab")
		)
		(fp_line
			(start -0.12065 0.2794)
			(end -0.12065 0.3048)
			(stroke
				(width 0.1)
				(type default)
			)
			(layer "F.Fab")
		)
		(fp_line
			(start -0.12065 -0.2794)
			(end 0.12065 -0.2794)
			(stroke
				(width 0.1)
				(type default)
			)
			(layer "F.Fab")
		)
		(fp_line
			(start -0.12065 -0.305054)
			(end -0.12065 -0.2794)
			(stroke
				(width 0.1)
				(type default)
			)
			(layer "F.Fab")
		)
		(fp_line
			(start -0.67945 0.3048)
			(end -0.67945 -0.305054)
			(stroke
				(width 0.1)
				(type default)
			)
			(layer "F.Fab")
		)
		(fp_line
			(start -0.67945 -0.305054)
			(end -0.12065 -0.305054)
			(stroke
				(width 0.1)
				(type default)
			)
			(layer "F.Fab")
		)
		(pad "1" smd circle
			(at -0.40005 0 180)
			(size 0 0)
			(layers "F.Cu" "F.Mask" "F.Paste")
			(net "SMB_2_BMC_GPU_BUF_R_SDA")
		)
		(pad "2" smd circle
			(at 0.40005 0 180)
			(size 0 0)
			(layers "F.Cu" "F.Mask" "F.Paste")
			(net "SMB_2_BMC_GPU_BUF_SDA")
		)
	)
)
